(kicad_pcb
	(version 20260206)
	(generator "pcbnew")
	(generator_version "10.0")
	(general
		(thickness 2.5)
		(legacy_teardrops no)
	)
	(paper "A4")
	(title_block
		(title "discovery-power-board-v1-revB — discovery.kicad_pcb")
		(comment 1 "Discovery / footprints 6-18 of 18")
	)
	(layers
		(0 "F.Cu" signal)
		(2 "B.Cu" signal)
		(9 "F.Adhes" user)
		(11 "B.Adhes" user)
		(13 "F.Paste" user)
		(15 "B.Paste" user)
		(5 "F.SilkS" user)
		(7 "B.SilkS" user)
		(1 "F.Mask" user)
		(3 "B.Mask" user)
		(17 "Dwgs.User" user)
		(19 "Cmts.User" user)
		(21 "Eco1.User" user)
		(23 "Eco2.User" user)
		(25 "Edge.Cuts" user)
		(27 "Margin" user)
		(31 "F.CrtYd" user)
		(29 "B.CrtYd" user)
		(35 "F.Fab" user)
		(33 "B.Fab" user)
	)
	(footprint "discovery:CONN_02x04_4.2mm"
		(layer "F.Cu")
		(at 28 63.3 -90)
		(property "Reference" "J3"
			(at 1.0922 0.97028 270)
			(layer "F.SilkS")
			(effects
				(font
					(size 1 1)
					(thickness 0.15)
				)
			)
		)
		(property "Value" "Conn_02x04_CPU"
			(at 10.69848 0.8509 270)
			(layer "F.Fab")
			(effects
				(font
					(size 1 1)
					(thickness 0.15)
				)
			)
		)
		(attr through_hole)
		(duplicate_pad_numbers_are_jumpers no)
		(fp_line
			(start 0 0)
			(end 18 0)
			(stroke
				(width 0.1)
				(type solid)
			)
			(layer "F.SilkS")
		)
		(fp_line
			(start 0 0)
			(end 0 -9.6)
			(stroke
				(width 0.1)
				(type solid)
			)
			(layer "F.SilkS")
		)
		(fp_line
			(start 18 0)
			(end 18 -9.6)
			(stroke
				(width 0.1)
				(type solid)
			)
			(layer "F.SilkS")
		)
		(fp_line
			(start 0 -9.6)
			(end 18 -9.6)
			(stroke
				(width 0.1)
				(type solid)
			)
			(layer "F.SilkS")
		)
		(fp_line
			(start 8.2 -11)
			(end 8.2 -9.6)
			(stroke
				(width 0.1)
				(type solid)
			)
			(layer "F.SilkS")
		)
		(fp_line
			(start 8.2 -11)
			(end 10.2 -11)
			(stroke
				(width 0.1)
				(type solid)
			)
			(layer "F.SilkS")
		)
		(fp_line
			(start 10.2 -11)
			(end 10.2 -9.6)
			(stroke
				(width 0.1)
				(type solid)
			)
			(layer "F.SilkS")
		)
		(fp_line
			(start -4 0.1)
			(end 22 0.1)
			(stroke
				(width 0.1)
				(type solid)
			)
			(layer "F.CrtYd")
		)
		(fp_line
			(start 22 0.1)
			(end 22 -11.05)
			(stroke
				(width 0.1)
				(type solid)
			)
			(layer "F.CrtYd")
		)
		(fp_line
			(start -4 -11.05)
			(end -4 0.1)
			(stroke
				(width 0.1)
				(type solid)
			)
			(layer "F.CrtYd")
		)
		(fp_line
			(start 22 -11.05)
			(end -4 -11.05)
			(stroke
				(width 0.1)
				(type solid)
			)
			(layer "F.CrtYd")
		)
		(pad "" np_thru_hole circle
			(at -2 -7.1 270)
			(size 4 4)
			(drill 3.03)
			(layers "*.Cu" "*.Mask")
		)
		(pad "" np_thru_hole circle
			(at 20 -7.1 270)
			(size 4 4)
			(drill 3.03)
			(layers "*.Cu" "*.Mask")
		)
		(pad "1" thru_hole circle
			(at 15.3 -2.7 270)
			(size 2.5 2.5)
			(drill 1.8)
			(layers "*.Cu" "*.Mask")
			(remove_unused_layers no)
			(net "GND")
		)
		(pad "2" thru_hole circle
			(at 11.1 -2.7 270)
			(size 2.5 2.5)
			(drill 1.8)
			(layers "*.Cu" "*.Mask")
			(remove_unused_layers no)
			(net "GND")
		)
		(pad "3" thru_hole circle
			(at 6.9 -2.7 270)
			(size 2.5 2.5)
			(drill 1.8)
			(layers "*.Cu" "*.Mask")
			(remove_unused_layers no)
			(net "GND")
		)
		(pad "4" thru_hole circle
			(at 2.7 -2.7 270)
			(size 2.5 2.5)
			(drill 1.8)
			(layers "*.Cu" "*.Mask")
			(remove_unused_layers no)
			(net "GND")
		)
		(pad "5" thru_hole circle
			(at 15.3 -6.9 270)
			(size 2.5 2.5)
			(drill 1.8)
			(layers "*.Cu" "*.Mask")
			(remove_unused_layers no)
			(net "+12V")
		)
		(pad "6" thru_hole circle
			(at 11.1 -6.9 270)
			(size 2.5 2.5)
			(drill 1.8)
			(layers "*.Cu" "*.Mask")
			(remove_unused_layers no)
			(net "+12V")
		)
		(pad "7" thru_hole circle
			(at 6.9 -6.9 270)
			(size 2.5 2.5)
			(drill 1.8)
			(layers "*.Cu" "*.Mask")
			(remove_unused_layers no)
			(net "+12V")
		)
		(pad "8" thru_hole circle
			(at 2.7 -6.9 270)
			(size 2.5 2.5)
			(drill 1.8)
			(layers "*.Cu" "*.Mask")
			(remove_unused_layers no)
			(net "+12V")
		)
	)
	(footprint "discovery:FixingPoint_Plated_Hole_D4.0mm"
		(layer "F.Cu")
		(at 145 145)
		(descr "Plated Hole as fixing Point, diameter 4.0mm")
		(tags "fixing point plated hole")
		(property "Reference" "W1"
			(at 3.81878 2.29224 0)
			(layer "F.SilkS")
			(effects
				(font
					(size 1 1)
					(thickness 0.15)
				)
			)
		)
		(property "Value" "Fixing hole"
			(at 0 3.55 0)
			(layer "F.Fab")
			(effects
				(font
					(size 1 1)
					(thickness 0.15)
				)
			)
		)
		(attr exclude_from_pos_files exclude_from_bom)
		(duplicate_pad_numbers_are_jumpers no)
		(fp_circle
			(center 0 0)
			(end 0 2.75)
			(stroke
				(width 0.12)
				(type solid)
			)
			(fill no)
			(layer "F.SilkS")
		)
		(fp_circle
			(center 0 0)
			(end 3 0)
			(stroke
				(width 0.05)
				(type solid)
			)
			(fill no)
			(layer "F.CrtYd")
		)
		(fp_text user "${REFERENCE}"
			(at 0 -3.55 0)
			(layer "F.Fab")
			(effects
				(font
					(size 1 1)
					(thickness 0.15)
				)
			)
		)
		(pad "1" thru_hole circle
			(at 0 0)
			(size 5 5)
			(drill 4)
			(layers "*.Cu" "*.Mask")
			(remove_unused_layers no)
			(net "GND")
		)
	)
	(footprint "discovery:FixingPoint_Plated_Hole_D4.0mm"
		(layer "F.Cu")
		(at 5 55)
		(descr "Plated Hole as fixing Point, diameter 4.0mm")
		(tags "fixing point plated hole")
		(property "Reference" "W2"
			(at 4.16432 -0.32904 0)
			(layer "F.SilkS")
			(effects
				(font
					(size 1 1)
					(thickness 0.15)
				)
			)
		)
		(property "Value" "Fixing hole"
			(at 0 3.55 0)
			(layer "F.Fab")
			(effects
				(font
					(size 1 1)
					(thickness 0.15)
				)
			)
		)
		(attr exclude_from_pos_files exclude_from_bom)
		(duplicate_pad_numbers_are_jumpers no)
		(fp_circle
			(center 0 0)
			(end 0 2.75)
			(stroke
				(width 0.12)
				(type solid)
			)
			(fill no)
			(layer "F.SilkS")
		)
		(fp_circle
			(center 0 0)
			(end 3 0)
			(stroke
				(width 0.05)
				(type solid)
			)
			(fill no)
			(layer "F.CrtYd")
		)
		(fp_text user "${REFERENCE}"
			(at 0 -3.55 0)
			(layer "F.Fab")
			(effects
				(font
					(size 1 1)
					(thickness 0.15)
				)
			)
		)
		(pad "1" thru_hole circle
			(at 0 0)
			(size 5 5)
			(drill 4)
			(layers "*.Cu" "*.Mask")
			(remove_unused_layers no)
			(net "GND")
		)
	)
	(footprint "discovery:FixingPoint_Plated_Hole_D4.0mm"
		(layer "F.Cu")
		(at 145 55)
		(descr "Plated Hole as fixing Point, diameter 4.0mm")
		(tags "fixing point plated hole")
		(property "Reference" "W3"
			(at 3.81878 2.29224 0)
			(layer "F.SilkS")
			(effects
				(font
					(size 1 1)
					(thickness 0.15)
				)
			)
		)
		(property "Value" "Fixing hole"
			(at 0 3.55 0)
			(layer "F.Fab")
			(effects
				(font
					(size 1 1)
					(thickness 0.15)
				)
			)
		)
		(attr exclude_from_pos_files exclude_from_bom)
		(duplicate_pad_numbers_are_jumpers no)
		(fp_circle
			(center 0 0)
			(end 0 2.75)
			(stroke
				(width 0.12)
				(type solid)
			)
			(fill no)
			(layer "F.SilkS")
		)
		(fp_circle
			(center 0 0)
			(end 3 0)
			(stroke
				(width 0.05)
				(type solid)
			)
			(fill no)
			(layer "F.CrtYd")
		)
		(fp_text user "${REFERENCE}"
			(at 0 -3.55 0)
			(layer "F.Fab")
			(effects
				(font
					(size 1 1)
					(thickness 0.15)
				)
			)
		)
		(pad "1" thru_hole circle
			(at 0 0)
			(size 5 5)
			(drill 4)
			(layers "*.Cu" "*.Mask")
			(remove_unused_layers no)
			(net "GND")
		)
	)
	(footprint "discovery:FixingPoint_Plated_Hole_D4.0mm"
		(layer "F.Cu")
		(at 5 145)
		(descr "Plated Hole as fixing Point, diameter 4.0mm")
		(tags "fixing point plated hole")
		(property "Reference" "W4"
			(at 3.81878 2.29224 0)
			(layer "F.SilkS")
			(effects
				(font
					(size 1 1)
					(thickness 0.15)
				)
			)
		)
		(property "Value" "Fixing hole"
			(at 0 3.55 0)
			(layer "F.Fab")
			(effects
				(font
					(size 1 1)
					(thickness 0.15)
				)
			)
		)
		(attr exclude_from_pos_files exclude_from_bom)
		(duplicate_pad_numbers_are_jumpers no)
		(fp_circle
			(center 0 0)
			(end 0 2.75)
			(stroke
				(width 0.12)
				(type solid)
			)
			(fill no)
			(layer "F.SilkS")
		)
		(fp_circle
			(center 0 0)
			(end 3 0)
			(stroke
				(width 0.05)
				(type solid)
			)
			(fill no)
			(layer "F.CrtYd")
		)
		(fp_text user "${REFERENCE}"
			(at 0 -3.55 0)
			(layer "F.Fab")
			(effects
				(font
					(size 1 1)
					(thickness 0.15)
				)
			)
		)
		(pad "1" thru_hole circle
			(at 0 0)
			(size 5 5)
			(drill 4)
			(layers "*.Cu" "*.Mask")
			(remove_unused_layers no)
			(net "GND")
		)
	)
	(footprint "discovery:fixing_hole"
		(layer "F.Cu")
		(at 60 67)
		(property "Reference" "W5"
			(at -4.4323 -7.4676 0)
			(layer "F.SilkS")
			(effects
				(font
					(size 1 1)
					(thickness 0.15)
				)
			)
		)
		(property "Value" "Cable hole"
			(at 5.3721 8.3312 0)
			(layer "F.Fab")
			(effects
				(font
					(size 1 1)
					(thickness 0.15)
				)
			)
		)
		(attr through_hole)
		(duplicate_pad_numbers_are_jumpers no)
		(fp_circle
			(center 0 0)
			(end 7.6 0)
			(stroke
				(width 0.1)
				(type solid)
			)
			(fill no)
			(layer "F.CrtYd")
		)
		(pad "1" thru_hole circle
			(at 0 0)
			(size 15 15)
			(drill 5.7)
			(layers "*.Cu" "*.Mask" "F.SilkS")
			(remove_unused_layers no)
			(net "+12V")
		)
	)
	(footprint "discovery:fixing_hole"
		(layer "F.Cu")
		(at 60 89.5)
		(property "Reference" "W6"
			(at -4.4323 -7.4676 0)
			(layer "F.SilkS")
			(effects
				(font
					(size 1 1)
					(thickness 0.15)
				)
			)
		)
		(property "Value" "Cable hole"
			(at 5.3721 8.3312 0)
			(layer "F.Fab")
			(effects
				(font
					(size 1 1)
					(thickness 0.15)
				)
			)
		)
		(attr through_hole)
		(duplicate_pad_numbers_are_jumpers no)
		(fp_circle
			(center 0 0)
			(end 7.6 0)
			(stroke
				(width 0.1)
				(type solid)
			)
			(fill no)
			(layer "F.CrtYd")
		)
		(pad "1" thru_hole circle
			(at 0 0)
			(size 15 15)
			(drill 5.7)
			(layers "*.Cu" "*.Mask" "F.SilkS")
			(remove_unused_layers no)
			(net "+12V")
		)
	)
	(footprint "discovery:fixing_hole"
		(layer "F.Cu")
		(at 60 112)
		(property "Reference" "W7"
			(at -4.4323 -7.4676 0)
			(layer "F.SilkS")
			(effects
				(font
					(size 1 1)
					(thickness 0.15)
				)
			)
		)
		(property "Value" "Cable hole"
			(at 5.3721 8.3312 0)
			(layer "F.Fab")
			(effects
				(font
					(size 1 1)
					(thickness 0.15)
				)
			)
		)
		(attr through_hole)
		(duplicate_pad_numbers_are_jumpers no)
		(fp_circle
			(center 0 0)
			(end 7.6 0)
			(stroke
				(width 0.1)
				(type solid)
			)
			(fill no)
			(layer "F.CrtYd")
		)
		(pad "1" thru_hole circle
			(at 0 0)
			(size 15 15)
			(drill 5.7)
			(layers "*.Cu" "*.Mask" "F.SilkS")
			(remove_unused_layers no)
			(net "+12V")
		)
	)
	(footprint "discovery:fixing_hole"
		(layer "F.Cu")
		(at 60 134.5)
		(property "Reference" "W8"
			(at -4.4323 -7.4676 0)
			(layer "F.SilkS")
			(effects
				(font
					(size 1 1)
					(thickness 0.15)
				)
			)
		)
		(property "Value" "Cable hole"
			(at 5.3721 8.3312 0)
			(layer "F.Fab")
			(effects
				(font
					(size 1 1)
					(thickness 0.15)
				)
			)
		)
		(attr through_hole)
		(duplicate_pad_numbers_are_jumpers no)
		(fp_circle
			(center 0 0)
			(end 7.6 0)
			(stroke
				(width 0.1)
				(type solid)
			)
			(fill no)
			(layer "F.CrtYd")
		)
		(pad "1" thru_hole circle
			(at 0 0)
			(size 15 15)
			(drill 5.7)
			(layers "*.Cu" "*.Mask" "F.SilkS")
			(remove_unused_layers no)
			(net "+12V")
		)
	)
	(footprint "discovery:fixing_hole"
		(layer "F.Cu")
		(at 120 64.25)
		(property "Reference" "W9"
			(at -4.4323 -7.4676 0)
			(layer "F.SilkS")
			(effects
				(font
					(size 1 1)
					(thickness 0.15)
				)
			)
		)
		(property "Value" "Cable hole"
			(at 5.3721 8.3312 0)
			(layer "F.Fab")
			(effects
				(font
					(size 1 1)
					(thickness 0.15)
				)
			)
		)
		(attr through_hole)
		(duplicate_pad_numbers_are_jumpers no)
		(fp_circle
			(center 0 0)
			(end 7.6 0)
			(stroke
				(width 0.1)
				(type solid)
			)
			(fill no)
			(layer "F.CrtYd")
		)
		(pad "1" thru_hole circle
			(at 0 0)
			(size 15 15)
			(drill 5.7)
			(layers "*.Cu" "*.Mask" "F.SilkS")
			(remove_unused_layers no)
			(net "GND")
		)
	)
	(footprint "discovery:fixing_hole"
		(layer "F.Cu")
		(at 120 86.75)
		(property "Reference" "W10"
			(at -4.4323 -7.4676 0)
			(layer "F.SilkS")
			(effects
				(font
					(size 1 1)
					(thickness 0.15)
				)
			)
		)
		(property "Value" "Cable hole"
			(at 5.3721 8.3312 0)
			(layer "F.Fab")
			(effects
				(font
					(size 1 1)
					(thickness 0.15)
				)
			)
		)
		(attr through_hole)
		(duplicate_pad_numbers_are_jumpers no)
		(fp_circle
			(center 0 0)
			(end 7.6 0)
			(stroke
				(width 0.1)
				(type solid)
			)
			(fill no)
			(layer "F.CrtYd")
		)
		(pad "1" thru_hole circle
			(at 0 0)
			(size 15 15)
			(drill 5.7)
			(layers "*.Cu" "*.Mask" "F.SilkS")
			(remove_unused_layers no)
			(net "GND")
		)
	)
	(footprint "discovery:fixing_hole"
		(layer "F.Cu")
		(at 120 131.75)
		(property "Reference" "W11"
			(at -4.4323 -7.4676 0)
			(layer "F.SilkS")
			(effects
				(font
					(size 1 1)
					(thickness 0.15)
				)
			)
		)
		(property "Value" "Cable hole"
			(at 5.3721 8.3312 0)
			(layer "F.Fab")
			(effects
				(font
					(size 1 1)
					(thickness 0.15)
				)
			)
		)
		(attr through_hole)
		(duplicate_pad_numbers_are_jumpers no)
		(fp_circle
			(center 0 0)
			(end 7.6 0)
			(stroke
				(width 0.1)
				(type solid)
			)
			(fill no)
			(layer "F.CrtYd")
		)
		(pad "1" thru_hole circle
			(at 0 0)
			(size 15 15)
			(drill 5.7)
			(layers "*.Cu" "*.Mask" "F.SilkS")
			(remove_unused_layers no)
			(net "GND")
		)
	)
	(footprint "discovery:fixing_hole"
		(layer "F.Cu")
		(at 120 109.25)
		(property "Reference" "W12"
			(at -4.4323 -7.4676 0)
			(layer "F.SilkS")
			(effects
				(font
					(size 1 1)
					(thickness 0.15)
				)
			)
		)
		(property "Value" "Cable hole"
			(at 5.3721 8.3312 0)
			(layer "F.Fab")
			(effects
				(font
					(size 1 1)
					(thickness 0.15)
				)
			)
		)
		(attr through_hole)
		(duplicate_pad_numbers_are_jumpers no)
		(fp_circle
			(center 0 0)
			(end 7.6 0)
			(stroke
				(width 0.1)
				(type solid)
			)
			(fill no)
			(layer "F.CrtYd")
		)
		(pad "1" thru_hole circle
			(at 0 0)
			(size 15 15)
			(drill 5.7)
			(layers "*.Cu" "*.Mask" "F.SilkS")
			(remove_unused_layers no)
			(net "GND")
		)
	)
)
